# S9S_MB_2U (Grand Teton) — schematic netlist excerpt (pin names and nets, part order shuffled) for the footprints in the layout excerpt that follows; sources: Cadence DE-HDL packaged netlist, KiCad conversion of 03242023_DA0F0TMBIJ0_F0T_Motherboard_J_brd_V01_OCP.brd

R820  Q_RES  1K 1% CHIP  pkg 0402LF  page 130 : A = PVCCD_HV_CPU1 ; B = RST_M_AB_CPU1_FPGA_N
C2067  Q_CAP  0.1UF 25V 10% X7R  pkg 0402  page 171 : A = P3V3_AUX ; B = GND

(kicad_pcb
	(version 20260206)
	(generator "pcbnew")
	(generator_version "10.0")
	(general
		(thickness 1.6)
		(legacy_teardrops no)
	)
	(paper "A4")
	(title_block
		(title "03242023_DA0F0TMBIJ0_F0T_Motherboard_J_brd_V01_OCP.brd")
		(comment 1 "Grand Teton / footprints 4153-4154 of 6105")
	)
	(layers
		(0 "F.Cu" signal "TOP")
		(4 "In1.Cu" signal "GND")
		(6 "In2.Cu" signal "IN1")
		(8 "In3.Cu" signal "GND1")
		(10 "In4.Cu" signal "IN2")
		(12 "In5.Cu" signal "GND2")
		(14 "In6.Cu" signal "IN3")
		(16 "In7.Cu" signal "GND3")
		(18 "In8.Cu" signal "VCC")
		(20 "In9.Cu" signal "VCC1")
		(22 "In10.Cu" signal "GND4")
		(24 "In11.Cu" signal "IN4")
		(26 "In12.Cu" signal "GND5")
		(28 "In13.Cu" signal "IN5")
		(30 "In14.Cu" signal "GND6")
		(32 "In15.Cu" signal "IN6")
		(34 "In16.Cu" signal "GND7")
		(2 "B.Cu" signal "BOTTOM")
		(9 "F.Adhes" user "F.Adhesive")
		(11 "B.Adhes" user "B.Adhesive")
		(13 "F.Paste" user "Package Geometry/Pastemask Top")
		(15 "B.Paste" user "Package Geometry/Pastemask Bottom")
		(5 "F.SilkS" user "Ref Des/Silkscreen Top")
		(7 "B.SilkS" user "Ref Des/Silkscreen Bottom")
		(1 "F.Mask" user "Board Geometry/Soldermask Top")
		(3 "B.Mask" user "Board Geometry/Soldermask Bottom")
		(17 "Dwgs.User" user "User.Drawings")
		(19 "Cmts.User" user "User.Comments")
		(21 "Eco1.User" user "User.Eco1")
		(23 "Eco2.User" user "User.Eco2")
		(25 "Edge.Cuts" user "Board Geometry/Outline")
		(27 "Margin" user)
		(31 "F.CrtYd" user "Package Geometry/Place Bound Top")
		(29 "B.CrtYd" user "Package Geometry/Place Bound Bottom")
		(35 "F.Fab" user "Ref Des/Assembly Top")
		(33 "B.Fab" user "Ref Des/Assembly Bottom")
	)
	(footprint ""
		(layer "B.Cu")
		(at 37.599366 -192.924176 -90)
		(property "Reference" "R820"
			(at 0 0 90)
			(layer "B.SilkS")
			(hide yes)
			(effects
				(font
					(size 1.27 1.27)
				)
				(justify mirror)
			)
		)
		(property "Value" ""
			(at 0 0 90)
			(layer "B.Fab")
			(effects
				(font
					(size 1.27 1.27)
				)
				(justify mirror)
			)
		)
		(duplicate_pad_numbers_are_jumpers no)
		(fp_line
			(start -0.7874 0.4064)
			(end 0.7874 0.4064)
			(stroke
				(width 0.1524)
				(type default)
			)
			(layer "B.SilkS")
		)
		(fp_line
			(start 0.7874 0.4064)
			(end 0.7874 -0.4064)
			(stroke
				(width 0.1524)
				(type default)
			)
			(layer "B.SilkS")
		)
		(fp_line
			(start -0.7874 -0.4064)
			(end -0.7874 0.4064)
			(stroke
				(width 0.1524)
				(type default)
			)
			(layer "B.SilkS")
		)
		(fp_line
			(start 0.7874 -0.4064)
			(end -0.7874 -0.4064)
			(stroke
				(width 0.1524)
				(type default)
			)
			(layer "B.SilkS")
		)
		(fp_line
			(start -0.67945 0.3048)
			(end -0.120396 0.3048)
			(stroke
				(width 0.1)
				(type default)
			)
			(layer "B.Fab")
		)
		(fp_line
			(start -0.120396 0.3048)
			(end -0.120396 0.2794)
			(stroke
				(width 0.1)
				(type default)
			)
			(layer "B.Fab")
		)
		(fp_line
			(start 0.12065 0.3048)
			(end 0.67945 0.3048)
			(stroke
				(width 0.1)
				(type default)
			)
			(layer "B.Fab")
		)
		(fp_line
			(start 0.67945 0.3048)
			(end 0.67945 -0.305054)
			(stroke
				(width 0.1)
				(type default)
			)
			(layer "B.Fab")
		)
		(fp_line
			(start -0.120396 0.2794)
			(end 0.12065 0.2794)
			(stroke
				(width 0.1)
				(type default)
			)
			(layer "B.Fab")
		)
		(fp_line
			(start 0.12065 0.2794)
			(end 0.12065 0.3048)
			(stroke
				(width 0.1)
				(type default)
			)
			(layer "B.Fab")
		)
		(fp_line
			(start -0.12065 -0.2794)
			(end -0.12065 -0.3048)
			(stroke
				(width 0.1)
				(type default)
			)
			(layer "B.Fab")
		)
		(fp_line
			(start 0.12065 -0.2794)
			(end -0.12065 -0.2794)
			(stroke
				(width 0.1)
				(type default)
			)
			(layer "B.Fab")
		)
		(fp_line
			(start -0.67945 -0.3048)
			(end -0.67945 0.3048)
			(stroke
				(width 0.1)
				(type default)
			)
			(layer "B.Fab")
		)
		(fp_line
			(start -0.12065 -0.3048)
			(end -0.67945 -0.3048)
			(stroke
				(width 0.1)
				(type default)
			)
			(layer "B.Fab")
		)
		(fp_line
			(start 0.12065 -0.305054)
			(end 0.12065 -0.2794)
			(stroke
				(width 0.1)
				(type default)
			)
			(layer "B.Fab")
		)
		(fp_line
			(start 0.67945 -0.305054)
			(end 0.12065 -0.305054)
			(stroke
				(width 0.1)
				(type default)
			)
			(layer "B.Fab")
		)
		(pad "1" smd circle
			(at 0.40005 0 90)
			(size 0 0)
			(layers "B.Cu" "B.Mask" "B.Paste")
			(net "PVCCD_HV_CPU1")
		)
		(pad "2" smd circle
			(at -0.40005 0 90)
			(size 0 0)
			(layers "B.Cu" "B.Mask" "B.Paste")
			(net "RST_M_AB_CPU1_FPGA_N")
		)
	)
	(footprint ""
		(layer "B.Cu")
		(at 216.20988 -53.177948)
		(property "Reference" "C2067"
			(at 0 0 0)
			(layer "B.SilkS")
			(hide yes)
			(effects
				(font
					(size 1.27 1.27)
				)
				(justify mirror)
			)
		)
		(property "Value" ""
			(at 0 0 0)
			(layer "B.Fab")
			(effects
				(font
					(size 1.27 1.27)
				)
				(justify mirror)
			)
		)
		(duplicate_pad_numbers_are_jumpers no)
		(fp_line
			(start -0.7874 -0.4064)
			(end -0.7874 0.4064)
			(stroke
				(width 0.1524)
				(type default)
			)
			(layer "B.SilkS")
		)
		(fp_line
			(start -0.7874 0.4064)
			(end 0.7874 0.4064)
			(stroke
				(width 0.1524)
				(type default)
			)
			(layer "B.SilkS")
		)
		(fp_line
			(start 0.7874 -0.4064)
			(end -0.7874 -0.4064)
			(stroke
				(width 0.1524)
				(type default)
			)
			(layer "B.SilkS")
		)
		(fp_line
			(start 0.7874 0.4064)
			(end 0.7874 -0.4064)
			(stroke
				(width 0.1524)
				(type default)
			)
			(layer "B.SilkS")
		)
		(fp_line
			(start -0.67945 -0.3048)
			(end -0.67945 0.3048)
			(stroke
				(width 0.1)
				(type default)
			)
			(layer "B.Fab")
		)
		(fp_line
			(start -0.67945 0.3048)
			(end -0.120396 0.3048)
			(stroke
				(width 0.1)
				(type default)
			)
			(layer "B.Fab")
		)
		(fp_line
			(start -0.12065 -0.3048)
			(end -0.67945 -0.3048)
			(stroke
				(width 0.1)
				(type default)
			)
			(layer "B.Fab")
		)
		(fp_line
			(start -0.12065 -0.2794)
			(end -0.12065 -0.3048)
			(stroke
				(width 0.1)
				(type default)
			)
			(layer "B.Fab")
		)
		(fp_line
			(start -0.120396 0.2794)
			(end 0.12065 0.2794)
			(stroke
				(width 0.1)
				(type default)
			)
			(layer "B.Fab")
		)
		(fp_line
			(start -0.120396 0.3048)
			(end -0.120396 0.2794)
			(stroke
				(width 0.1)
				(type default)
			)
			(layer "B.Fab")
		)
		(fp_line
			(start 0.12065 -0.305054)
			(end 0.12065 -0.2794)
			(stroke
				(width 0.1)
				(type default)
			)
			(layer "B.Fab")
		)
		(fp_line
			(start 0.12065 -0.2794)
			(end -0.12065 -0.2794)
			(stroke
				(width 0.1)
				(type default)
			)
			(layer "B.Fab")
		)
		(fp_line
			(start 0.12065 0.2794)
			(end 0.12065 0.3048)
			(stroke
				(width 0.1)
				(type default)
			)
			(layer "B.Fab")
		)
		(fp_line
			(start 0.12065 0.3048)
			(end 0.67945 0.3048)
			(stroke
				(width 0.1)
				(type default)
			)
			(layer "B.Fab")
		)
		(fp_line
			(start 0.67945 -0.305054)
			(end 0.12065 -0.305054)
			(stroke
				(width 0.1)
				(type default)
			)
			(layer "B.Fab")
		)
		(fp_line
			(start 0.67945 0.3048)
			(end 0.67945 -0.305054)
			(stroke
				(width 0.1)
				(type default)
			)
			(layer "B.Fab")
		)
		(pad "1" smd circle
			(at 0.40005 0 180)
			(size 0 0)
			(layers "B.Cu" "B.Mask" "B.Paste")
			(net "P3V3_AUX")
		)
		(pad "2" smd circle
			(at -0.40005 0 180)
			(size 0 0)
			(layers "B.Cu" "B.Mask" "B.Paste")
			(net "GND")
		)
	)
)
